# T6G (Grand Teton) — schematic netlist excerpt (pin names and nets, part order shuffled) for the footprints in the layout excerpt that follows; sources: Cadence DE-HDL packaged netlist, KiCad conversion of 04192023_DAF0TMB3IC0_F0TG_MB_C_brd_V02_OCP.brd

R1450  Q_RES  10K 5% CHIP  pkg 0402LF  page 259 : A = P3V3_AUX ; B = PWRGD_P12V_MEM_CPU0_EN_N
PC2204  Q_CAP  10UF 16V 10% X6S  pkg C0805  page 147 : A = P3V3_E1S_0_R ; B = GND
R8096  Q_RES  100K 1% CHIP  pkg 0402LF  page 142 : A = OCP_V3_2_P3V3_R1_PWRGD ; B = GND

(kicad_pcb
	(version 20260206)
	(generator "pcbnew")
	(generator_version "10.0")
	(general
		(thickness 1.6)
		(legacy_teardrops no)
	)
	(paper "A4")
	(title_block
		(title "04192023_DAF0TMB3IC0_F0TG_MB_C_brd_V02_OCP.brd")
		(comment 1 "Grand Teton / footprints 3645-3647 of 8354")
	)
	(layers
		(0 "F.Cu" signal "TOP")
		(4 "In1.Cu" signal "GND")
		(6 "In2.Cu" signal "IN1")
		(8 "In3.Cu" signal "GND1")
		(10 "In4.Cu" signal "IN2")
		(12 "In5.Cu" signal "GND2")
		(14 "In6.Cu" signal "IN3")
		(16 "In7.Cu" signal "GND3")
		(18 "In8.Cu" signal "VCC")
		(20 "In9.Cu" signal "VCC1")
		(22 "In10.Cu" signal "GND4")
		(24 "In11.Cu" signal "IN4")
		(26 "In12.Cu" signal "GND5")
		(28 "In13.Cu" signal "IN5")
		(30 "In14.Cu" signal "GND6")
		(32 "In15.Cu" signal "IN6")
		(34 "In16.Cu" signal "GND7")
		(2 "B.Cu" signal "BOTTOM")
		(9 "F.Adhes" user "F.Adhesive")
		(11 "B.Adhes" user "B.Adhesive")
		(13 "F.Paste" user "Package Geometry/Pastemask Top")
		(15 "B.Paste" user "Package Geometry/Pastemask Bottom")
		(5 "F.SilkS" user "Ref Des/Silkscreen Top")
		(7 "B.SilkS" user "Ref Des/Silkscreen Bottom")
		(1 "F.Mask" user "Board Geometry/Soldermask Top")
		(3 "B.Mask" user "Board Geometry/Soldermask Bottom")
		(17 "Dwgs.User" user "User.Drawings")
		(19 "Cmts.User" user "User.Comments")
		(21 "Eco1.User" user "User.Eco1")
		(23 "Eco2.User" user "User.Eco2")
		(25 "Edge.Cuts" user "Board Geometry/Outline")
		(27 "Margin" user)
		(31 "F.CrtYd" user "Package Geometry/Place Bound Top")
		(29 "B.CrtYd" user "Package Geometry/Place Bound Bottom")
		(35 "F.Fab" user "Ref Des/Assembly Top")
		(33 "B.Fab" user "Ref Des/Assembly Bottom")
	)
	(footprint ""
		(layer "F.Cu")
		(at 78.867 -66.802 180)
		(property "Reference" "R8096"
			(at 0 0 180)
			(layer "F.SilkS")
			(hide yes)
			(effects
				(font
					(size 1.27 1.27)
				)
			)
		)
		(property "Value" ""
			(at 0 0 180)
			(layer "F.Fab")
			(effects
				(font
					(size 1.27 1.27)
				)
			)
		)
		(duplicate_pad_numbers_are_jumpers no)
		(fp_line
			(start 0.7874 0.4064)
			(end -0.7874 0.4064)
			(stroke
				(width 0.1524)
				(type default)
			)
			(layer "F.SilkS")
		)
		(fp_line
			(start 0.7874 -0.4064)
			(end 0.7874 0.4064)
			(stroke
				(width 0.1524)
				(type default)
			)
			(layer "F.SilkS")
		)
		(fp_line
			(start -0.7874 0.4064)
			(end -0.7874 -0.4064)
			(stroke
				(width 0.1524)
				(type default)
			)
			(layer "F.SilkS")
		)
		(fp_line
			(start -0.7874 -0.4064)
			(end 0.7874 -0.4064)
			(stroke
				(width 0.1524)
				(type default)
			)
			(layer "F.SilkS")
		)
		(fp_line
			(start 0.67945 0.3048)
			(end 0.120396 0.3048)
			(stroke
				(width 0.1)
				(type default)
			)
			(layer "F.Fab")
		)
		(fp_line
			(start 0.67945 -0.3048)
			(end 0.67945 0.3048)
			(stroke
				(width 0.1)
				(type default)
			)
			(layer "F.Fab")
		)
		(fp_line
			(start 0.12065 -0.2794)
			(end 0.12065 -0.3048)
			(stroke
				(width 0.1)
				(type default)
			)
			(layer "F.Fab")
		)
		(fp_line
			(start 0.12065 -0.3048)
			(end 0.67945 -0.3048)
			(stroke
				(width 0.1)
				(type default)
			)
			(layer "F.Fab")
		)
		(fp_line
			(start 0.120396 0.3048)
			(end 0.120396 0.2794)
			(stroke
				(width 0.1)
				(type default)
			)
			(layer "F.Fab")
		)
		(fp_line
			(start 0.120396 0.2794)
			(end -0.12065 0.2794)
			(stroke
				(width 0.1)
				(type default)
			)
			(layer "F.Fab")
		)
		(fp_line
			(start -0.12065 0.3048)
			(end -0.67945 0.3048)
			(stroke
				(width 0.1)
				(type default)
			)
			(layer "F.Fab")
		)
		(fp_line
			(start -0.12065 0.2794)
			(end -0.12065 0.3048)
			(stroke
				(width 0.1)
				(type default)
			)
			(layer "F.Fab")
		)
		(fp_line
			(start -0.12065 -0.2794)
			(end 0.12065 -0.2794)
			(stroke
				(width 0.1)
				(type default)
			)
			(layer "F.Fab")
		)
		(fp_line
			(start -0.12065 -0.305054)
			(end -0.12065 -0.2794)
			(stroke
				(width 0.1)
				(type default)
			)
			(layer "F.Fab")
		)
		(fp_line
			(start -0.67945 0.3048)
			(end -0.67945 -0.305054)
			(stroke
				(width 0.1)
				(type default)
			)
			(layer "F.Fab")
		)
		(fp_line
			(start -0.67945 -0.305054)
			(end -0.12065 -0.305054)
			(stroke
				(width 0.1)
				(type default)
			)
			(layer "F.Fab")
		)
		(pad "1" smd circle
			(at -0.40005 0 180)
			(size 0 0)
			(layers "F.Cu" "F.Mask" "F.Paste")
			(net "OCP_V3_2_P3V3_R1_PWRGD")
		)
		(pad "2" smd circle
			(at 0.40005 0 180)
			(size 0 0)
			(layers "F.Cu" "F.Mask" "F.Paste")
			(net "GND")
		)
	)
	(footprint ""
		(layer "F.Cu")
		(at 102.154736 -119.499126 90)
		(property "Reference" "R1450"
			(at 0 0 90)
			(layer "F.SilkS")
			(hide yes)
			(effects
				(font
					(size 1.27 1.27)
				)
			)
		)
		(property "Value" ""
			(at 0 0 90)
			(layer "F.Fab")
			(effects
				(font
					(size 1.27 1.27)
				)
			)
		)
		(duplicate_pad_numbers_are_jumpers no)
		(fp_line
			(start 0.7874 -0.4064)
			(end 0.7874 0.4064)
			(stroke
				(width 0.1524)
				(type default)
			)
			(layer "F.SilkS")
		)
		(fp_line
			(start -0.7874 -0.4064)
			(end 0.7874 -0.4064)
			(stroke
				(width 0.1524)
				(type default)
			)
			(layer "F.SilkS")
		)
		(fp_line
			(start 0.7874 0.4064)
			(end -0.7874 0.4064)
			(stroke
				(width 0.1524)
				(type default)
			)
			(layer "F.SilkS")
		)
		(fp_line
			(start -0.7874 0.4064)
			(end -0.7874 -0.4064)
			(stroke
				(width 0.1524)
				(type default)
			)
			(layer "F.SilkS")
		)
		(fp_line
			(start -0.12065 -0.305054)
			(end -0.12065 -0.2794)
			(stroke
				(width 0.1)
				(type default)
			)
			(layer "F.Fab")
		)
		(fp_line
			(start -0.67945 -0.305054)
			(end -0.12065 -0.305054)
			(stroke
				(width 0.1)
				(type default)
			)
			(layer "F.Fab")
		)
		(fp_line
			(start 0.67945 -0.3048)
			(end 0.67945 0.3048)
			(stroke
				(width 0.1)
				(type default)
			)
			(layer "F.Fab")
		)
		(fp_line
			(start 0.12065 -0.3048)
			(end 0.67945 -0.3048)
			(stroke
				(width 0.1)
				(type default)
			)
			(layer "F.Fab")
		)
		(fp_line
			(start 0.12065 -0.2794)
			(end 0.12065 -0.3048)
			(stroke
				(width 0.1)
				(type default)
			)
			(layer "F.Fab")
		)
		(fp_line
			(start -0.12065 -0.2794)
			(end 0.12065 -0.2794)
			(stroke
				(width 0.1)
				(type default)
			)
			(layer "F.Fab")
		)
		(fp_line
			(start 0.120396 0.2794)
			(end -0.12065 0.2794)
			(stroke
				(width 0.1)
				(type default)
			)
			(layer "F.Fab")
		)
		(fp_line
			(start -0.12065 0.2794)
			(end -0.12065 0.3048)
			(stroke
				(width 0.1)
				(type default)
			)
			(layer "F.Fab")
		)
		(fp_line
			(start 0.67945 0.3048)
			(end 0.120396 0.3048)
			(stroke
				(width 0.1)
				(type default)
			)
			(layer "F.Fab")
		)
		(fp_line
			(start 0.120396 0.3048)
			(end 0.120396 0.2794)
			(stroke
				(width 0.1)
				(type default)
			)
			(layer "F.Fab")
		)
		(fp_line
			(start -0.12065 0.3048)
			(end -0.67945 0.3048)
			(stroke
				(width 0.1)
				(type default)
			)
			(layer "F.Fab")
		)
		(fp_line
			(start -0.67945 0.3048)
			(end -0.67945 -0.305054)
			(stroke
				(width 0.1)
				(type default)
			)
			(layer "F.Fab")
		)
		(pad "1" smd circle
			(at -0.40005 0 90)
			(size 0 0)
			(layers "F.Cu" "F.Mask" "F.Paste")
			(net "P3V3_AUX")
		)
		(pad "2" smd circle
			(at 0.40005 0 90)
			(size 0 0)
			(layers "F.Cu" "F.Mask" "F.Paste")
			(net "PWRGD_P12V_MEM_CPU0_EN_N")
		)
	)
	(footprint ""
		(layer "F.Cu")
		(at 196.457824 -65.225168 -90)
		(property "Reference" "PC2204"
			(at 0 0 270)
			(layer "F.SilkS")
			(hide yes)
			(effects
				(font
					(size 1.27 1.27)
				)
			)
		)
		(property "Value" ""
			(at 0 0 270)
			(layer "F.Fab")
			(effects
				(font
					(size 1.27 1.27)
				)
			)
		)
		(duplicate_pad_numbers_are_jumpers no)
		(fp_line
			(start -1.524 0.762)
			(end -1.524 -0.762)
			(stroke
				(width 0.1524)
				(type default)
			)
			(layer "F.SilkS")
		)
		(fp_line
			(start 1.524 0.762)
			(end -1.524 0.762)
			(stroke
				(width 0.1524)
				(type default)
			)
			(layer "F.SilkS")
		)
		(fp_line
			(start -1.524 -0.762)
			(end 1.524 -0.762)
			(stroke
				(width 0.1524)
				(type default)
			)
			(layer "F.SilkS")
		)
		(fp_line
			(start 1.524 -0.762)
			(end 1.524 0.762)
			(stroke
				(width 0.1524)
				(type default)
			)
			(layer "F.SilkS")
		)
		(fp_line
			(start -1.1049 0.724916)
			(end 1.1049 0.724916)
			(stroke
				(width 0.1)
				(type default)
			)
			(layer "F.Fab")
		)
		(fp_line
			(start 1.1049 0.724916)
			(end 1.1049 -0.724916)
			(stroke
				(width 0.1)
				(type default)
			)
			(layer "F.Fab")
		)
		(fp_line
			(start -1.1049 -0.724916)
			(end -1.1049 0.724916)
			(stroke
				(width 0.1)
				(type default)
			)
			(layer "F.Fab")
		)
		(fp_line
			(start 1.1049 -0.724916)
			(end -1.1049 -0.724916)
			(stroke
				(width 0.1)
				(type default)
			)
			(layer "F.Fab")
		)
		(pad "1" smd rect
			(at -0.889 0 90)
			(size 1.016 1.27)
			(layers "F.Cu" "F.Mask" "F.Paste")
			(net "P3V3_E1S_0_R")
		)
		(pad "2" smd rect
			(at 0.889 0 90)
			(size 1.016 1.27)
			(layers "F.Cu" "F.Mask" "F.Paste")
			(net "GND")
		)
	)
)
